(kicad_pcb
	(version 20241229)
	(generator "pcbnew")
	(generator_version "9.0")
	(general
		(thickness 1.61)
		(legacy_teardrops no)
	)
	(paper "A3")
	(title_block
		(title "RDIMM DDR5 Tester")
		(date "2026-05-21")
		(rev "2.2.0")
		(company "Antmicro")
		(comment 9 "footprints 263-266 of 796")
	)
	(layers
		(0 "F.Cu" signal)
		(4 "In1.Cu" power)
		(6 "In2.Cu" mixed)
		(8 "In3.Cu" power)
		(10 "In4.Cu" mixed)
		(12 "In5.Cu" power)
		(14 "In6.Cu" mixed)
		(16 "In7.Cu" power)
		(18 "In8.Cu" power)
		(20 "In9.Cu" mixed)
		(22 "In10.Cu" power)
		(2 "B.Cu" signal)
		(9 "F.Adhes" user "F.Adhesive")
		(11 "B.Adhes" user "B.Adhesive")
		(13 "F.Paste" user)
		(15 "B.Paste" user)
		(5 "F.SilkS" user "F.Silkscreen")
		(7 "B.SilkS" user "B.Silkscreen")
		(1 "F.Mask" user)
		(3 "B.Mask" user)
		(17 "Dwgs.User" user "User.Drawings")
		(19 "Cmts.User" user "User.Comments")
		(21 "Eco1.User" user "User.Eco1")
		(23 "Eco2.User" user "User.Eco2")
		(25 "Edge.Cuts" user)
		(27 "Margin" user)
		(31 "F.CrtYd" user "F.Courtyard")
		(29 "B.CrtYd" user "B.Courtyard")
		(35 "F.Fab" user)
		(33 "B.Fab" user)
	)
	(footprint "antmicro-footprints:C_0805_2012Metric"
		(layer "F.Cu")
		(at 219.325001 187.669999)
		(descr "Capacitor SMD 0805")
		(tags "capacitor SMD 0805")
		(property "Reference" "C28"
			(at -4.475001 0.470001 0)
			(layer "F.SilkS")
			(effects
				(font
					(size 0.7 0.7)
					(thickness 0.15)
				)
				(justify left bottom)
			)
		)
		(property "Value" "C_22u_25V_0805"
			(at -2.055717 1.963152 0)
			(layer "F.Fab")
			(effects
				(font
					(size 0.7 0.7)
					(thickness 0.15)
				)
				(justify left bottom)
			)
		)
		(property "Datasheet" "https://product.samsungsem.com/mlcc/CL21A226MAYNNN.do"
			(at 0 0 0)
			(layer "F.Fab")
			(hide yes)
			(effects
				(font
					(size 1.27 1.27)
					(thickness 0.15)
				)
			)
		)
		(property "MPN" "CL21A226MAYNNNE"
			(at 0 0 0)
			(unlocked yes)
			(layer "F.Fab")
			(hide yes)
			(effects
				(font
					(size 1 1)
					(thickness 0.15)
				)
			)
		)
		(property "Manufacturer" "Samsung Electro-Mechanics"
			(at 0 0 0)
			(unlocked yes)
			(layer "F.Fab")
			(hide yes)
			(effects
				(font
					(size 1 1)
					(thickness 0.15)
				)
			)
		)
		(property "License" "Apache-2.0"
			(at 0 0 0)
			(unlocked yes)
			(layer "F.Fab")
			(hide yes)
			(effects
				(font
					(size 1 1)
					(thickness 0.15)
				)
			)
		)
		(property "Author" "Antmicro"
			(at 0 0 0)
			(unlocked yes)
			(layer "F.Fab")
			(hide yes)
			(effects
				(font
					(size 1 1)
					(thickness 0.15)
				)
			)
		)
		(property "Val" "22u"
			(at 0 0 0)
			(unlocked yes)
			(layer "F.Fab")
			(hide yes)
			(effects
				(font
					(size 1 1)
					(thickness 0.15)
				)
			)
		)
		(property "Voltage" "25V"
			(at 0 0 0)
			(unlocked yes)
			(layer "F.Fab")
			(hide yes)
			(effects
				(font
					(size 1 1)
					(thickness 0.15)
				)
			)
		)
		(property "Dielectric" "X5R"
			(at 0 0 0)
			(unlocked yes)
			(layer "F.Fab")
			(hide yes)
			(effects
				(font
					(size 1 1)
					(thickness 0.15)
				)
			)
		)
		(property "Public" "False"
			(at 0 0 0)
			(unlocked yes)
			(layer "F.Fab")
			(hide yes)
			(effects
				(font
					(size 1 1)
					(thickness 0.15)
				)
			)
		)
		(sheetname "/Supply/DC-DC VCCINT/")
		(sheetfile "dc-dc-vccint.kicad_sch")
		(attr smd)
		(fp_line
			(start -0.3 -0.7)
			(end 0.3 -0.7)
			(stroke
				(width 0.15)
				(type solid)
			)
			(layer "F.SilkS")
		)
		(fp_line
			(start -0.3 0.7)
			(end 0.3 0.7)
			(stroke
				(width 0.15)
				(type solid)
			)
			(layer "F.SilkS")
		)
		(fp_rect
			(start 1.95 -0.9)
			(end -1.95 0.9)
			(stroke
				(width 0.05)
				(type default)
			)
			(fill no)
			(layer "F.CrtYd")
		)
		(fp_rect
			(start -0.95 -0.675)
			(end 0.95 0.675)
			(stroke
				(width 0.15)
				(type solid)
			)
			(fill no)
			(layer "F.Fab")
		)
		(fp_text user "${REFERENCE}"
			(at -1.9 3.947 0)
			(layer "F.Fab")
			(effects
				(font
					(size 0.7 0.7)
					(thickness 0.15)
				)
				(justify left bottom)
			)
		)
		(fp_text user "Author: Antmicro"
			(at -1.9 5.947 0)
			(layer "F.Fab")
			(effects
				(font
					(size 0.7 0.7)
					(thickness 0.15)
				)
				(justify left bottom)
			)
		)
		(fp_text user "License: Apache-2.0"
			(at -1.9 4.947 0)
			(layer "F.Fab")
			(effects
				(font
					(size 0.7 0.7)
					(thickness 0.15)
				)
				(justify left bottom)
			)
		)
		(pad "1" smd roundrect
			(at -1.1 0)
			(size 1.2 1.3)
			(layers "F.Cu" "F.Mask" "F.Paste")
			(roundrect_rratio 0.25)
			(net 1 "GND")
			(pintype "passive")
		)
		(pad "2" smd roundrect
			(at 1.1 0)
			(size 1.2 1.3)
			(layers "F.Cu" "F.Mask" "F.Paste")
			(roundrect_rratio 0.25)
			(net 35 "VDC")
			(pintype "passive")
		)
	)
	(footprint "antmicro-footprints:R_0402_1005Metric"
		(layer "F.Cu")
		(at 120 170.775 90)
		(descr "Resistor SMD 0402")
		(tags "resistor SMD 0402")
		(property "Reference" "R247"
			(at 1.375 0.025 90)
			(layer "F.SilkS")
			(effects
				(font
					(size 0.7 0.7)
					(thickness 0.15)
				)
				(justify left bottom)
			)
		)
		(property "Value" "R_0R_0402"
			(at -1.011843 1.772047 90)
			(layer "F.Fab")
			(effects
				(font
					(size 0.7 0.7)
					(thickness 0.15)
				)
				(justify left bottom)
			)
		)
		(property "Datasheet" "https://industrial.panasonic.com/cdbs/www-data/pdf/RDA0000/AOA0000C301.pdf"
			(at 0 0 90)
			(layer "F.Fab")
			(hide yes)
			(effects
				(font
					(size 1.27 1.27)
					(thickness 0.15)
				)
			)
		)
		(property "MPN" "ERJ2GE0R00X"
			(at 0 0 90)
			(unlocked yes)
			(layer "F.Fab")
			(hide yes)
			(effects
				(font
					(size 1 1)
					(thickness 0.15)
				)
			)
		)
		(property "Manufacturer" "Panasonic"
			(at 0 0 90)
			(unlocked yes)
			(layer "F.Fab")
			(hide yes)
			(effects
				(font
					(size 1 1)
					(thickness 0.15)
				)
			)
		)
		(property "License" "Apache-2.0"
			(at 0 0 90)
			(unlocked yes)
			(layer "F.Fab")
			(hide yes)
			(effects
				(font
					(size 1 1)
					(thickness 0.15)
				)
			)
		)
		(property "Author" "Antmicro"
			(at 0 0 90)
			(unlocked yes)
			(layer "F.Fab")
			(hide yes)
			(effects
				(font
					(size 1 1)
					(thickness 0.15)
				)
			)
		)
		(property "Val" "0R"
			(at 0 0 90)
			(unlocked yes)
			(layer "F.Fab")
			(hide yes)
			(effects
				(font
					(size 1 1)
					(thickness 0.15)
				)
			)
		)
		(property "Tolerance" "~"
			(at 0 0 90)
			(unlocked yes)
			(layer "F.Fab")
			(hide yes)
			(effects
				(font
					(size 1 1)
					(thickness 0.15)
				)
			)
		)
		(property "Current" "1A"
			(at 0 0 90)
			(unlocked yes)
			(layer "F.Fab")
			(hide yes)
			(effects
				(font
					(size 1 1)
					(thickness 0.15)
				)
			)
		)
		(sheetname "/HDMI + SD Card/")
		(sheetfile "hdmi-sd-card.kicad_sch")
		(attr smd exclude_from_bom dnp)
		(fp_rect
			(start -0.925 -0.47)
			(end 0.925 0.47)
			(stroke
				(width 0.05)
				(type default)
			)
			(fill no)
			(layer "F.CrtYd")
		)
		(fp_rect
			(start -0.5 -0.25)
			(end 0.5 0.25)
			(stroke
				(width 0.15)
				(type solid)
			)
			(fill no)
			(layer "F.Fab")
		)
		(fp_text user "${REFERENCE}"
			(at -0.95 3.168 90)
			(layer "F.Fab")
			(effects
				(font
					(size 0.7 0.7)
					(thickness 0.15)
				)
				(justify left bottom)
			)
		)
		(fp_text user "Author: Antmicro"
			(at -0.95 4.169 90)
			(layer "F.Fab")
			(effects
				(font
					(size 0.7 0.7)
					(thickness 0.15)
				)
				(justify left bottom)
			)
		)
		(fp_text user "License: Apache-2.0"
			(at -0.95 5.169 90)
			(layer "F.Fab")
			(effects
				(font
					(size 0.7 0.7)
					(thickness 0.15)
				)
				(justify left bottom)
			)
		)
		(pad "1" smd roundrect
			(at -0.48 0 90)
			(size 0.59 0.64)
			(layers "F.Cu" "F.Mask" "F.Paste")
			(roundrect_rratio 0.25)
			(net 810 "/HDMI + SD Card/HDMI_VDD")
			(pintype "passive")
		)
		(pad "2" smd roundrect
			(at 0.48 0 90)
			(size 0.59 0.64)
			(layers "F.Cu" "F.Mask" "F.Paste")
			(roundrect_rratio 0.25)
			(net 687 "VDDQ")
			(pintype "passive")
		)
	)
	(footprint "antmicro-footprints:C_0603_1608Metric"
		(layer "F.Cu")
		(at 221.955 168.73 180)
		(descr "Capacitor SMD 0603")
		(tags "capacitor 0603")
		(property "Reference" "C219"
			(at -3.42 -3.015001 0)
			(layer "F.SilkS")
			(effects
				(font
					(size 0.7 0.7)
					(thickness 0.15)
				)
				(justify right bottom)
			)
		)
		(property "Value" "C_22u_0603"
			(at -1.42757 1.770288 0)
			(layer "F.Fab")
			(effects
				(font
					(size 0.7 0.7)
					(thickness 0.15)
				)
				(justify right bottom)
			)
		)
		(property "Datasheet" "https://www.murata.com/products/productdetail?partno=GRM188R60J226MEA0%23"
			(at 0 0 180)
			(layer "F.Fab")
			(hide yes)
			(effects
				(font
					(size 1.27 1.27)
					(thickness 0.15)
				)
			)
		)
		(property "Manufacturer" "Murata"
			(at 0 0 180)
			(unlocked yes)
			(layer "F.Fab")
			(hide yes)
			(effects
				(font
					(size 1 1)
					(thickness 0.15)
				)
			)
		)
		(property "MPN" "GRM188R60J226MEA0D"
			(at 0 0 180)
			(unlocked yes)
			(layer "F.Fab")
			(hide yes)
			(effects
				(font
					(size 1 1)
					(thickness 0.15)
				)
			)
		)
		(property "Val" "22u"
			(at 0 0 180)
			(unlocked yes)
			(layer "F.Fab")
			(hide yes)
			(effects
				(font
					(size 1 1)
					(thickness 0.15)
				)
			)
		)
		(property "License" "Apache-2.0"
			(at 0 0 180)
			(unlocked yes)
			(layer "F.Fab")
			(hide yes)
			(effects
				(font
					(size 1 1)
					(thickness 0.15)
				)
			)
		)
		(property "Author" "Antmicro"
			(at 0 0 180)
			(unlocked yes)
			(layer "F.Fab")
			(hide yes)
			(effects
				(font
					(size 1 1)
					(thickness 0.15)
				)
			)
		)
		(property "Voltage" ""
			(at 0 0 180)
			(unlocked yes)
			(layer "F.Fab")
			(hide yes)
			(effects
				(font
					(size 1 1)
					(thickness 0.15)
				)
			)
		)
		(property "Dielectric" ""
			(at 0 0 180)
			(unlocked yes)
			(layer "F.Fab")
			(hide yes)
			(effects
				(font
					(size 1 1)
					(thickness 0.15)
				)
			)
		)
		(sheetname "/Supply/DC-DC VCCINT/")
		(sheetfile "dc-dc-vccint.kicad_sch")
		(attr smd)
		(fp_line
			(start -0.15 0.4)
			(end 0.15 0.4)
			(stroke
				(width 0.15)
				(type solid)
			)
			(layer "F.SilkS")
		)
		(fp_line
			(start -0.15 -0.4)
			(end 0.15 -0.4)
			(stroke
				(width 0.15)
				(type solid)
			)
			(layer "F.SilkS")
		)
		(fp_rect
			(start -1.25 -0.65)
			(end 1.25 0.65)
			(stroke
				(width 0.05)
				(type solid)
			)
			(fill no)
			(layer "F.CrtYd")
		)
		(fp_rect
			(start -0.8 -0.4)
			(end 0.8 0.4)
			(stroke
				(width 0.15)
				(type solid)
			)
			(fill no)
			(layer "F.Fab")
		)
		(fp_text user "License: Apache-2.0"
			(at -1.682 5.895 180)
			(layer "F.Fab")
			(effects
				(font
					(size 0.7 0.7)
					(thickness 0.15)
				)
				(justify left bottom)
			)
		)
		(fp_text user "${REFERENCE}"
			(at -1.682 3.895 180)
			(layer "F.Fab")
			(effects
				(font
					(size 0.7 0.7)
					(thickness 0.15)
				)
				(justify left bottom)
			)
		)
		(fp_text user "Author: Antmicro"
			(at -1.682 4.894 180)
			(layer "F.Fab")
			(effects
				(font
					(size 0.7 0.7)
					(thickness 0.15)
				)
				(justify left bottom)
			)
		)
		(pad "1" smd roundrect
			(at -0.7 0 180)
			(size 0.8 1)
			(layers "F.Cu" "F.Mask" "F.Paste")
			(roundrect_rratio 0.2)
			(net 1 "GND")
			(pintype "passive")
		)
		(pad "2" smd roundrect
			(at 0.7 0 180)
			(size 0.8 1)
			(layers "F.Cu" "F.Mask" "F.Paste")
			(roundrect_rratio 0.2)
			(net 223 "/Supply/DC-DC VCCINT/0V85_REG0")
			(pintype "passive")
		)
	)
	(footprint "antmicro-footprints:TQFN-25_4x5mm"
		(layer "F.Cu")
		(at 219.250001 182.245001 -90)
		(property "Reference" "U4"
			(at 3.614999 -2.199999 0)
			(unlocked yes)
			(layer "F.SilkS")
			(effects
				(font
					(size 0.7 0.7)
					(thickness 0.15)
				)
				(justify left bottom)
			)
		)
		(property "Value" "MP8796B"
			(at 12.501 7.605 270)
			(unlocked yes)
			(layer "F.Fab")
			(effects
				(font
					(size 0.7 0.7)
					(thickness 0.15)
				)
				(justify left bottom)
			)
		)
		(property "Datasheet" "https://www.monolithicpower.com/en/documentview/productdocument/index/version/2/document_type/Datasheet/lang/en/sku/MP8796B/"
			(at 0 0 270)
			(layer "F.Fab")
			(hide yes)
			(effects
				(font
					(size 1.27 1.27)
					(thickness 0.15)
				)
			)
		)
		(property "MPN" "MP8796BGVT-0000-Z"
			(at 0 0 270)
			(unlocked yes)
			(layer "F.Fab")
			(hide yes)
			(effects
				(font
					(size 1 1)
					(thickness 0.15)
				)
			)
		)
		(property "Manufacturer" "Monolithic Power Systems"
			(at 0 0 270)
			(unlocked yes)
			(layer "F.Fab")
			(hide yes)
			(effects
				(font
					(size 1 1)
					(thickness 0.15)
				)
			)
		)
		(property "Author" "Antmicro"
			(at 0 0 270)
			(unlocked yes)
			(layer "F.Fab")
			(hide yes)
			(effects
				(font
					(size 1 1)
					(thickness 0.15)
				)
			)
		)
		(property "License" "Apache-2.0"
			(at 0 0 270)
			(unlocked yes)
			(layer "F.Fab")
			(hide yes)
			(effects
				(font
					(size 1 1)
					(thickness 0.15)
				)
			)
		)
		(sheetname "/Supply/DC-DC VCCINT/")
		(sheetfile "dc-dc-vccint.kicad_sch")
		(attr smd)
		(fp_line
			(start -2.1 2.2)
			(end -2.1 1.7)
			(stroke
				(width 0.15)
				(type solid)
			)
			(layer "F.SilkS")
		)
		(fp_line
			(start 2.1 2.2)
			(end 2.1 1.7)
			(stroke
				(width 0.15)
				(type solid)
			)
			(layer "F.SilkS")
		)
		(fp_line
			(start -2.1 -1.7)
			(end -2.1 -2.2)
			(stroke
				(width 0.15)
				(type solid)
			)
			(layer "F.SilkS")
		)
		(fp_line
			(start 2.1 -2.2)
			(end 2.1 -1.7)
			(stroke
				(width 0.15)
				(type solid)
			)
			(layer "F.SilkS")
		)
		(fp_circle
			(center -2.34 -2.59)
			(end -2.29 -2.59)
			(stroke
				(width 0.15)
				(type solid)
			)
			(fill yes)
			(layer "F.SilkS")
		)
		(fp_rect
			(start -2.5 -2.75)
			(end 2.55 2.76)
			(stroke
				(width 0.05)
				(type solid)
			)
			(fill no)
			(layer "F.CrtYd")
		)
		(fp_text user "Author: Antmicro"
			(at -2.67 5.79 270)
			(layer "F.Fab")
			(effects
				(font
					(size 0.7 0.7)
					(thickness 0.15)
				)
				(justify left bottom)
			)
		)
		(fp_text user "License: Apache-2.0"
			(at -2.67 8.19 270)
			(layer "F.Fab")
			(effects
				(font
					(size 0.7 0.7)
					(thickness 0.15)
				)
				(justify left bottom)
			)
		)
		(fp_text user "${REFERENCE}"
			(at -2.67 6.99 270)
			(unlocked yes)
			(layer "F.Fab")
			(effects
				(font
					(size 0.7 0.7)
					(thickness 0.15)
				)
				(justify left bottom)
			)
		)
		(pad "1" smd roundrect
			(at -1.2 -1.195 90)
			(size 2.1 0.4)
			(layers "F.Cu" "F.Mask" "F.Paste")
			(roundrect_rratio 0.25)
			(net 35 "VDC")
			(pinfunction "IN")
			(pintype "power_in")
		)
		(pad "2" smd roundrect
			(at -1.2 -0.545 90)
			(size 2.1 0.4)
			(layers "F.Cu" "F.Mask" "F.Paste")
			(roundrect_rratio 0.25)
			(net 165 "Net-(C215-Pad2)")
			(pinfunction "SW")
			(pintype "passive")
		)
		(pad "3" smd roundrect
			(at -1.2 0.555 90)
			(size 2.1 0.4)
			(layers "F.Cu" "F.Mask" "F.Paste")
			(roundrect_rratio 0.25)
			(net 165 "Net-(C215-Pad2)")
			(pinfunction "SW")
			(pintype "passive")
		)
		(pad "4" smd roundrect
			(at -1.2 1.205 90)
			(size 2.1 0.4)
			(layers "F.Cu" "F.Mask" "F.Paste")
			(roundrect_rratio 0.25)
			(net 1 "GND")
			(pinfunction "P_{GND}")
			(pintype "passive")
		)
		(pad "5" smd roundrect
			(at -1.7 2.355)
			(size 0.9 0.3)
			(layers "F.Cu" "F.Mask" "F.Paste")
			(roundrect_rratio 0.25)
			(net 222 "Net-(U4-V_{DRV})")
			(pinfunction "V_{DRV}")
			(pintype "passive")
		)
		(pad "6" smd roundrect
			(at -1.2 2.355)
			(size 0.9 0.2)
			(layers "F.Cu" "F.Mask" "F.Paste")
			(roundrect_rratio 0.25)
			(net 749 "/I^{2}C + I3C/PWR.SCL")
			(pinfunction "SCL")
			(pintype "open_collector")
		)
		(pad "7" smd roundrect
			(at -0.8 2.355)
			(size 0.9 0.2)
			(layers "F.Cu" "F.Mask" "F.Paste")
			(roundrect_rratio 0.25)
			(net 533 "/I^{2}C + I3C/PWR.SDA")
			(pinfunction "SDA")
			(pintype "open_collector")
		)
		(pad "8" smd roundrect
			(at -0.4 2.355)
			(size 0.9 0.2)
			(layers "F.Cu" "F.Mask" "F.Paste")
			(roundrect_rratio 0.25)
			(net 741 "/Supply/DC-DC VCCINT/PWR.~{ALT}1")
			(pinfunction "~{ALT}")
			(pintype "open_collector")
		)
		(pad "9" smd roundrect
			(at 0 2.355)
			(size 0.9 0.2)
			(layers "F.Cu" "F.Mask" "F.Paste")
			(roundrect_rratio 0.25)
			(net 168 "/Supply/EN1")
			(pinfunction "CTRL")
			(pintype "input")
		)
		(pad "10" smd roundrect
			(at 0.4 2.355)
			(size 0.9 0.2)
			(layers "F.Cu" "F.Mask" "F.Paste")
			(roundrect_rratio 0.25)
			(net 482 "PG1")
			(pinfunction "PG")
			(pintype "open_collector")
		)
		(pad "11" smd roundrect
			(at 0.8 2.355)
			(size 0.9 0.2)
			(layers "F.Cu" "F.Mask" "F.Paste")
			(roundrect_rratio 0.25)
			(net 721 "/Supply/DC-DC VCCINT/PASS0")
			(pinfunction "PASS")
			(pintype "output")
		)
		(pad "12" smd roundrect
			(at 1.2 2.355)
			(size 0.9 0.2)
			(layers "F.Cu" "F.Mask" "F.Paste")
			(roundrect_rratio 0.25)
			(net 724 "/Supply/DC-DC VCCINT/TAKE0")
			(pinfunction "TAKE")
			(pintype "input")
		)
		(pad "13" smd roundrect
			(at 1.7 2.355)
			(size 0.9 0.3)
			(layers "F.Cu" "F.Mask" "F.Paste")
			(roundrect_rratio 0.25)
			(net 742 "/Supply/DC-DC VCCINT/SET")
			(pinfunction "SET")
			(pintype "bidirectional")
		)
		(pad "14" smd roundrect
			(at 1.2 1.205 90)
			(size 2.1 0.4)
			(layers "F.Cu" "F.Mask" "F.Paste")
			(roundrect_rratio 0.25)
			(net 1 "GND")
			(pinfunction "P_{GND}")
			(pintype "power_in")
		)
		(pad "15" smd roundrect
			(at 1.25 0.005 90)
			(size 2.1 0.4)
			(layers "F.Cu" "F.Mask" "F.Paste")
			(roundrect_rratio 0.25)
			(net 1 "GND")
			(pinfunction "P_{GND}")
			(pintype "passive")
		)
		(pad "16" smd roundrect
			(at 1.2 -1.195 90)
			(size 2.1 0.4)
			(layers "F.Cu" "F.Mask" "F.Paste")
			(roundrect_rratio 0.25)
			(net 35 "VDC")
			(pinfunction "IN")
			(pintype "passive")
		)
		(pad "17" smd roundrect
			(at 1.7 -2.345)
			(size 0.9 0.3)
			(layers "F.Cu" "F.Mask" "F.Paste")
			(roundrect_rratio 0.25)
			(net 1 "GND")
			(pinfunction "~{PS}")
			(pintype "passive")
		)
		(pad "18" smd roundrect
			(at 1.2 -2.345)
			(size 0.9 0.2)
			(layers "F.Cu" "F.Mask" "F.Paste")
			(roundrect_rratio 0.25)
			(net 727 "Net-(U4-ADDR)")
			(pinfunction "ADDR")
			(pintype "passive")
		)
		(pad "19" smd roundrect
			(at 0.8 -2.345)
			(size 0.9 0.2)
			(layers "F.Cu" "F.Mask" "F.Paste")
			(roundrect_rratio 0.25)
			(net 743 "/Supply/DC-DC VCCINT/I_{SUM}")
			(pinfunction "I_{SUM}")
			(pintype "passive")
		)
		(pad "20" smd roundrect
			(at 0.4 -2.345)
			(size 0.9 0.2)
			(layers "F.Cu" "F.Mask" "F.Paste")
			(roundrect_rratio 0.25)
			(net 725 "Net-(U4-I_{REF})")
			(pinfunction "I_{REF}")
			(pintype "passive")
		)
		(pad "21" smd roundrect
			(at 0 -2.345)
			(size 0.9 0.2)
			(layers "F.Cu" "F.Mask" "F.Paste")
			(roundrect_rratio 0.25)
			(net 755 "/Supply/DC-DC VCCINT/VREF-")
			(pinfunction "V_{OSNS}-")
			(pintype "passive")
		)
		(pad "22" smd roundrect
			(at -0.4 -2.345)
			(size 0.9 0.2)
			(layers "F.Cu" "F.Mask" "F.Paste")
			(roundrect_rratio 0.25)
			(net 226 "/Supply/DC-DC VCCINT/V_{0SNS+}")
			(pinfunction "V_{OSNS}+")
			(pintype "passive")
		)
		(pad "23" smd roundrect
			(at -0.8 -2.345)
			(size 0.9 0.2)
			(layers "F.Cu" "F.Mask" "F.Paste")
			(roundrect_rratio 0.25)
			(net 1 "GND")
			(pinfunction "A_{GND}")
			(pintype "power_in")
		)
		(pad "24" smd roundrect
			(at -1.2 -2.345)
			(size 0.9 0.2)
			(layers "F.Cu" "F.Mask" "F.Paste")
			(roundrect_rratio 0.25)
			(net 163 "/Supply/DC-DC VCCINT/V_{CC}")
			(pinfunction "V_{CC}")
			(pintype "power_out")
		)
		(pad "25" smd roundrect
			(at -1.7 -2.345)
			(size 0.9 0.3)
			(layers "F.Cu" "F.Mask" "F.Paste")
			(roundrect_rratio 0.25)
			(net 164 "Net-(U4-BST)")
			(pinfunction "BST")
			(pintype "passive")
		)
	)
)
